(kicad_pcb
	(version 20260206)
	(generator "pcbnew")
	(generator_version "10.0")
	(general
		(thickness 1.6)
		(legacy_teardrops no)
	)
	(paper "A4")
	(title_block
		(title "03242023_DA0F0TMBIJ0_F0T_Motherboard_J_brd_V01_OCP.brd")
		(comment 1 "Grand Teton / footprints 4898-4904 of 6105")
	)
	(layers
		(0 "F.Cu" signal "TOP")
		(4 "In1.Cu" signal "GND")
		(6 "In2.Cu" signal "IN1")
		(8 "In3.Cu" signal "GND1")
		(10 "In4.Cu" signal "IN2")
		(12 "In5.Cu" signal "GND2")
		(14 "In6.Cu" signal "IN3")
		(16 "In7.Cu" signal "GND3")
		(18 "In8.Cu" signal "VCC")
		(20 "In9.Cu" signal "VCC1")
		(22 "In10.Cu" signal "GND4")
		(24 "In11.Cu" signal "IN4")
		(26 "In12.Cu" signal "GND5")
		(28 "In13.Cu" signal "IN5")
		(30 "In14.Cu" signal "GND6")
		(32 "In15.Cu" signal "IN6")
		(34 "In16.Cu" signal "GND7")
		(2 "B.Cu" signal "BOTTOM")
		(9 "F.Adhes" user "F.Adhesive")
		(11 "B.Adhes" user "B.Adhesive")
		(13 "F.Paste" user "Package Geometry/Pastemask Top")
		(15 "B.Paste" user "Package Geometry/Pastemask Bottom")
		(5 "F.SilkS" user "Ref Des/Silkscreen Top")
		(7 "B.SilkS" user "Ref Des/Silkscreen Bottom")
		(1 "F.Mask" user "Board Geometry/Soldermask Top")
		(3 "B.Mask" user "Board Geometry/Soldermask Bottom")
		(17 "Dwgs.User" user "User.Drawings")
		(19 "Cmts.User" user "User.Comments")
		(21 "Eco1.User" user "User.Eco1")
		(23 "Eco2.User" user "User.Eco2")
		(25 "Edge.Cuts" user "Board Geometry/Outline")
		(27 "Margin" user)
		(31 "F.CrtYd" user "Package Geometry/Place Bound Top")
		(29 "B.CrtYd" user "Package Geometry/Place Bound Bottom")
		(35 "F.Fab" user "Ref Des/Assembly Top")
		(33 "B.Fab" user "Ref Des/Assembly Bottom")
	)
	(footprint ""
		(layer "B.Cu")
		(at 367.012474 -334.693514 -90)
		(property "Reference" "PR146"
			(at 0 0 90)
			(layer "B.SilkS")
			(hide yes)
			(effects
				(font
					(size 1.27 1.27)
				)
				(justify mirror)
			)
		)
		(property "Value" ""
			(at 0 0 90)
			(layer "B.Fab")
			(effects
				(font
					(size 1.27 1.27)
				)
				(justify mirror)
			)
		)
		(duplicate_pad_numbers_are_jumpers no)
		(fp_line
			(start -0.7874 0.4064)
			(end 0.7874 0.4064)
			(stroke
				(width 0.1524)
				(type default)
			)
			(layer "B.SilkS")
		)
		(fp_line
			(start 0.7874 0.4064)
			(end 0.7874 -0.4064)
			(stroke
				(width 0.1524)
				(type default)
			)
			(layer "B.SilkS")
		)
		(fp_line
			(start -0.7874 -0.4064)
			(end -0.7874 0.4064)
			(stroke
				(width 0.1524)
				(type default)
			)
			(layer "B.SilkS")
		)
		(fp_line
			(start 0.7874 -0.4064)
			(end -0.7874 -0.4064)
			(stroke
				(width 0.1524)
				(type default)
			)
			(layer "B.SilkS")
		)
		(fp_line
			(start -0.67945 0.3048)
			(end -0.120396 0.3048)
			(stroke
				(width 0.1)
				(type default)
			)
			(layer "B.Fab")
		)
		(fp_line
			(start -0.120396 0.3048)
			(end -0.120396 0.2794)
			(stroke
				(width 0.1)
				(type default)
			)
			(layer "B.Fab")
		)
		(fp_line
			(start 0.12065 0.3048)
			(end 0.67945 0.3048)
			(stroke
				(width 0.1)
				(type default)
			)
			(layer "B.Fab")
		)
		(fp_line
			(start 0.67945 0.3048)
			(end 0.67945 -0.305054)
			(stroke
				(width 0.1)
				(type default)
			)
			(layer "B.Fab")
		)
		(fp_line
			(start -0.120396 0.2794)
			(end 0.12065 0.2794)
			(stroke
				(width 0.1)
				(type default)
			)
			(layer "B.Fab")
		)
		(fp_line
			(start 0.12065 0.2794)
			(end 0.12065 0.3048)
			(stroke
				(width 0.1)
				(type default)
			)
			(layer "B.Fab")
		)
		(fp_line
			(start -0.12065 -0.2794)
			(end -0.12065 -0.3048)
			(stroke
				(width 0.1)
				(type default)
			)
			(layer "B.Fab")
		)
		(fp_line
			(start 0.12065 -0.2794)
			(end -0.12065 -0.2794)
			(stroke
				(width 0.1)
				(type default)
			)
			(layer "B.Fab")
		)
		(fp_line
			(start -0.67945 -0.3048)
			(end -0.67945 0.3048)
			(stroke
				(width 0.1)
				(type default)
			)
			(layer "B.Fab")
		)
		(fp_line
			(start -0.12065 -0.3048)
			(end -0.67945 -0.3048)
			(stroke
				(width 0.1)
				(type default)
			)
			(layer "B.Fab")
		)
		(fp_line
			(start 0.12065 -0.305054)
			(end 0.12065 -0.2794)
			(stroke
				(width 0.1)
				(type default)
			)
			(layer "B.Fab")
		)
		(fp_line
			(start 0.67945 -0.305054)
			(end 0.12065 -0.305054)
			(stroke
				(width 0.1)
				(type default)
			)
			(layer "B.Fab")
		)
		(pad "1" smd circle
			(at 0.40005 0 90)
			(size 0 0)
			(layers "B.Cu" "B.Mask" "B.Paste")
			(net "PVCCIN_CPU0_PVCC")
		)
		(pad "2" smd circle
			(at -0.40005 0 90)
			(size 0 0)
			(layers "B.Cu" "B.Mask" "B.Paste")
			(net "PVCCIN_CPU0_VDD4")
		)
	)
	(footprint ""
		(layer "B.Cu")
		(at 154.48915 -192.79362 -90)
		(property "Reference" "R3023"
			(at 0 0 90)
			(layer "B.SilkS")
			(hide yes)
			(effects
				(font
					(size 1.27 1.27)
				)
				(justify mirror)
			)
		)
		(property "Value" ""
			(at 0 0 90)
			(layer "B.Fab")
			(effects
				(font
					(size 1.27 1.27)
				)
				(justify mirror)
			)
		)
		(duplicate_pad_numbers_are_jumpers no)
		(fp_line
			(start -0.7874 0.4064)
			(end 0.7874 0.4064)
			(stroke
				(width 0.1524)
				(type default)
			)
			(layer "B.SilkS")
		)
		(fp_line
			(start 0.7874 0.4064)
			(end 0.7874 -0.4064)
			(stroke
				(width 0.1524)
				(type default)
			)
			(layer "B.SilkS")
		)
		(fp_line
			(start -0.7874 -0.4064)
			(end -0.7874 0.4064)
			(stroke
				(width 0.1524)
				(type default)
			)
			(layer "B.SilkS")
		)
		(fp_line
			(start 0.7874 -0.4064)
			(end -0.7874 -0.4064)
			(stroke
				(width 0.1524)
				(type default)
			)
			(layer "B.SilkS")
		)
		(fp_line
			(start -0.67945 0.3048)
			(end -0.120396 0.3048)
			(stroke
				(width 0.1)
				(type default)
			)
			(layer "B.Fab")
		)
		(fp_line
			(start -0.120396 0.3048)
			(end -0.120396 0.2794)
			(stroke
				(width 0.1)
				(type default)
			)
			(layer "B.Fab")
		)
		(fp_line
			(start 0.12065 0.3048)
			(end 0.67945 0.3048)
			(stroke
				(width 0.1)
				(type default)
			)
			(layer "B.Fab")
		)
		(fp_line
			(start 0.67945 0.3048)
			(end 0.67945 -0.305054)
			(stroke
				(width 0.1)
				(type default)
			)
			(layer "B.Fab")
		)
		(fp_line
			(start -0.120396 0.2794)
			(end 0.12065 0.2794)
			(stroke
				(width 0.1)
				(type default)
			)
			(layer "B.Fab")
		)
		(fp_line
			(start 0.12065 0.2794)
			(end 0.12065 0.3048)
			(stroke
				(width 0.1)
				(type default)
			)
			(layer "B.Fab")
		)
		(fp_line
			(start -0.12065 -0.2794)
			(end -0.12065 -0.3048)
			(stroke
				(width 0.1)
				(type default)
			)
			(layer "B.Fab")
		)
		(fp_line
			(start 0.12065 -0.2794)
			(end -0.12065 -0.2794)
			(stroke
				(width 0.1)
				(type default)
			)
			(layer "B.Fab")
		)
		(fp_line
			(start -0.67945 -0.3048)
			(end -0.67945 0.3048)
			(stroke
				(width 0.1)
				(type default)
			)
			(layer "B.Fab")
		)
		(fp_line
			(start -0.12065 -0.3048)
			(end -0.67945 -0.3048)
			(stroke
				(width 0.1)
				(type default)
			)
			(layer "B.Fab")
		)
		(fp_line
			(start 0.12065 -0.305054)
			(end 0.12065 -0.2794)
			(stroke
				(width 0.1)
				(type default)
			)
			(layer "B.Fab")
		)
		(fp_line
			(start 0.67945 -0.305054)
			(end 0.12065 -0.305054)
			(stroke
				(width 0.1)
				(type default)
			)
			(layer "B.Fab")
		)
		(pad "1" smd circle
			(at 0.40005 0 90)
			(size 0 0)
			(layers "B.Cu" "B.Mask" "B.Paste")
			(net "H_CPU_PM_FAST_WAKE_N")
		)
		(pad "2" smd circle
			(at -0.40005 0 90)
			(size 0 0)
			(layers "B.Cu" "B.Mask" "B.Paste")
			(net "H_CPU1_PM_FAST_WAKE_N")
		)
	)
	(footprint ""
		(layer "B.Cu")
		(at 184.962546 -344.733626 -90)
		(property "Reference" "PC1204_P1_3"
			(at 0 0 90)
			(layer "B.SilkS")
			(hide yes)
			(effects
				(font
					(size 1.27 1.27)
				)
				(justify mirror)
			)
		)
		(property "Value" ""
			(at 0 0 90)
			(layer "B.Fab")
			(effects
				(font
					(size 1.27 1.27)
				)
				(justify mirror)
			)
		)
		(duplicate_pad_numbers_are_jumpers no)
		(fp_line
			(start -0.7874 0.4064)
			(end 0.7874 0.4064)
			(stroke
				(width 0.1524)
				(type default)
			)
			(layer "B.SilkS")
		)
		(fp_line
			(start 0.7874 0.4064)
			(end 0.7874 -0.4064)
			(stroke
				(width 0.1524)
				(type default)
			)
			(layer "B.SilkS")
		)
		(fp_line
			(start -0.7874 -0.4064)
			(end -0.7874 0.4064)
			(stroke
				(width 0.1524)
				(type default)
			)
			(layer "B.SilkS")
		)
		(fp_line
			(start 0.7874 -0.4064)
			(end -0.7874 -0.4064)
			(stroke
				(width 0.1524)
				(type default)
			)
			(layer "B.SilkS")
		)
		(fp_line
			(start -0.67945 0.3048)
			(end -0.120396 0.3048)
			(stroke
				(width 0.1)
				(type default)
			)
			(layer "B.Fab")
		)
		(fp_line
			(start -0.120396 0.3048)
			(end -0.120396 0.2794)
			(stroke
				(width 0.1)
				(type default)
			)
			(layer "B.Fab")
		)
		(fp_line
			(start 0.12065 0.3048)
			(end 0.67945 0.3048)
			(stroke
				(width 0.1)
				(type default)
			)
			(layer "B.Fab")
		)
		(fp_line
			(start 0.67945 0.3048)
			(end 0.67945 -0.305054)
			(stroke
				(width 0.1)
				(type default)
			)
			(layer "B.Fab")
		)
		(fp_line
			(start -0.120396 0.2794)
			(end 0.12065 0.2794)
			(stroke
				(width 0.1)
				(type default)
			)
			(layer "B.Fab")
		)
		(fp_line
			(start 0.12065 0.2794)
			(end 0.12065 0.3048)
			(stroke
				(width 0.1)
				(type default)
			)
			(layer "B.Fab")
		)
		(fp_line
			(start -0.12065 -0.2794)
			(end -0.12065 -0.3048)
			(stroke
				(width 0.1)
				(type default)
			)
			(layer "B.Fab")
		)
		(fp_line
			(start 0.12065 -0.2794)
			(end -0.12065 -0.2794)
			(stroke
				(width 0.1)
				(type default)
			)
			(layer "B.Fab")
		)
		(fp_line
			(start -0.67945 -0.3048)
			(end -0.67945 0.3048)
			(stroke
				(width 0.1)
				(type default)
			)
			(layer "B.Fab")
		)
		(fp_line
			(start -0.12065 -0.3048)
			(end -0.67945 -0.3048)
			(stroke
				(width 0.1)
				(type default)
			)
			(layer "B.Fab")
		)
		(fp_line
			(start 0.12065 -0.305054)
			(end 0.12065 -0.2794)
			(stroke
				(width 0.1)
				(type default)
			)
			(layer "B.Fab")
		)
		(fp_line
			(start 0.67945 -0.305054)
			(end 0.12065 -0.305054)
			(stroke
				(width 0.1)
				(type default)
			)
			(layer "B.Fab")
		)
		(pad "1" smd circle
			(at 0.40005 0 90)
			(size 0 0)
			(layers "B.Cu" "B.Mask" "B.Paste")
			(net "PVCCFA_EHV_FIVRA_CPU1")
		)
		(pad "2" smd circle
			(at -0.40005 0 90)
			(size 0 0)
			(layers "B.Cu" "B.Mask" "B.Paste")
			(net "GND")
		)
	)
	(footprint ""
		(layer "B.Cu")
		(at 435.255924 -180.958998 90)
		(property "Reference" "R2409"
			(at 0 0 90)
			(layer "B.SilkS")
			(hide yes)
			(effects
				(font
					(size 1.27 1.27)
				)
				(justify mirror)
			)
		)
		(property "Value" ""
			(at 0 0 90)
			(layer "B.Fab")
			(effects
				(font
					(size 1.27 1.27)
				)
				(justify mirror)
			)
		)
		(duplicate_pad_numbers_are_jumpers no)
		(fp_line
			(start 0.7874 -0.4064)
			(end -0.7874 -0.4064)
			(stroke
				(width 0.1524)
				(type default)
			)
			(layer "B.SilkS")
		)
		(fp_line
			(start -0.7874 -0.4064)
			(end -0.7874 0.4064)
			(stroke
				(width 0.1524)
				(type default)
			)
			(layer "B.SilkS")
		)
		(fp_line
			(start 0.7874 0.4064)
			(end 0.7874 -0.4064)
			(stroke
				(width 0.1524)
				(type default)
			)
			(layer "B.SilkS")
		)
		(fp_line
			(start -0.7874 0.4064)
			(end 0.7874 0.4064)
			(stroke
				(width 0.1524)
				(type default)
			)
			(layer "B.SilkS")
		)
		(fp_line
			(start 0.67945 -0.305054)
			(end 0.12065 -0.305054)
			(stroke
				(width 0.1)
				(type default)
			)
			(layer "B.Fab")
		)
		(fp_line
			(start 0.12065 -0.305054)
			(end 0.12065 -0.2794)
			(stroke
				(width 0.1)
				(type default)
			)
			(layer "B.Fab")
		)
		(fp_line
			(start -0.12065 -0.3048)
			(end -0.67945 -0.3048)
			(stroke
				(width 0.1)
				(type default)
			)
			(layer "B.Fab")
		)
		(fp_line
			(start -0.67945 -0.3048)
			(end -0.67945 0.3048)
			(stroke
				(width 0.1)
				(type default)
			)
			(layer "B.Fab")
		)
		(fp_line
			(start 0.12065 -0.2794)
			(end -0.12065 -0.2794)
			(stroke
				(width 0.1)
				(type default)
			)
			(layer "B.Fab")
		)
		(fp_line
			(start -0.12065 -0.2794)
			(end -0.12065 -0.3048)
			(stroke
				(width 0.1)
				(type default)
			)
			(layer "B.Fab")
		)
		(fp_line
			(start 0.12065 0.2794)
			(end 0.12065 0.3048)
			(stroke
				(width 0.1)
				(type default)
			)
			(layer "B.Fab")
		)
		(fp_line
			(start -0.120396 0.2794)
			(end 0.12065 0.2794)
			(stroke
				(width 0.1)
				(type default)
			)
			(layer "B.Fab")
		)
		(fp_line
			(start 0.67945 0.3048)
			(end 0.67945 -0.305054)
			(stroke
				(width 0.1)
				(type default)
			)
			(layer "B.Fab")
		)
		(fp_line
			(start 0.12065 0.3048)
			(end 0.67945 0.3048)
			(stroke
				(width 0.1)
				(type default)
			)
			(layer "B.Fab")
		)
		(fp_line
			(start -0.120396 0.3048)
			(end -0.120396 0.2794)
			(stroke
				(width 0.1)
				(type default)
			)
			(layer "B.Fab")
		)
		(fp_line
			(start -0.67945 0.3048)
			(end -0.120396 0.3048)
			(stroke
				(width 0.1)
				(type default)
			)
			(layer "B.Fab")
		)
		(pad "1" smd circle
			(at 0.40005 0 270)
			(size 0 0)
			(layers "B.Cu" "B.Mask" "B.Paste")
			(net "P3V3_AUX")
		)
		(pad "2" smd circle
			(at -0.40005 0 270)
			(size 0 0)
			(layers "B.Cu" "B.Mask" "B.Paste")
			(net "PWRGD_PVNN_MAIN_CPU0_R")
		)
	)
	(footprint ""
		(layer "B.Cu")
		(at 100.195126 -333.639922 90)
		(property "Reference" "PC567_P1_1"
			(at 0 0 90)
			(layer "B.SilkS")
			(hide yes)
			(effects
				(font
					(size 1.27 1.27)
				)
				(justify mirror)
			)
		)
		(property "Value" ""
			(at 0 0 90)
			(layer "B.Fab")
			(effects
				(font
					(size 1.27 1.27)
				)
				(justify mirror)
			)
		)
		(duplicate_pad_numbers_are_jumpers no)
		(fp_line
			(start 1.524 -0.762)
			(end -1.524 -0.762)
			(stroke
				(width 0.1524)
				(type default)
			)
			(layer "B.SilkS")
		)
		(fp_line
			(start -1.524 -0.762)
			(end -1.524 0.762)
			(stroke
				(width 0.1524)
				(type default)
			)
			(layer "B.SilkS")
		)
		(fp_line
			(start 1.524 0.762)
			(end 1.524 -0.762)
			(stroke
				(width 0.1524)
				(type default)
			)
			(layer "B.SilkS")
		)
		(fp_line
			(start -1.524 0.762)
			(end 1.524 0.762)
			(stroke
				(width 0.1524)
				(type default)
			)
			(layer "B.SilkS")
		)
		(fp_line
			(start 1.1049 -0.724916)
			(end 1.1049 0.724916)
			(stroke
				(width 0.1)
				(type default)
			)
			(layer "B.Fab")
		)
		(fp_line
			(start -1.1049 -0.724916)
			(end 1.1049 -0.724916)
			(stroke
				(width 0.1)
				(type default)
			)
			(layer "B.Fab")
		)
		(fp_line
			(start 1.1049 0.724916)
			(end -1.1049 0.724916)
			(stroke
				(width 0.1)
				(type default)
			)
			(layer "B.Fab")
		)
		(fp_line
			(start -1.1049 0.724916)
			(end -1.1049 -0.724916)
			(stroke
				(width 0.1)
				(type default)
			)
			(layer "B.Fab")
		)
		(pad "1" smd rect
			(at 0.889 0 90)
			(size 1.016 1.27)
			(layers "B.Cu" "B.Mask" "B.Paste")
			(net "SW_P12V_PVCCIN_CPU1_FLT")
		)
		(pad "2" smd rect
			(at -0.889 0 90)
			(size 1.016 1.27)
			(layers "B.Cu" "B.Mask" "B.Paste")
			(net "GND")
		)
	)
	(footprint ""
		(layer "B.Cu")
		(at 158.83636 -257.89509 -90)
		(property "Reference" "C473"
			(at 0 0 90)
			(layer "B.SilkS")
			(hide yes)
			(effects
				(font
					(size 1.27 1.27)
				)
				(justify mirror)
			)
		)
		(property "Value" ""
			(at 0 0 90)
			(layer "B.Fab")
			(effects
				(font
					(size 1.27 1.27)
				)
				(justify mirror)
			)
		)
		(duplicate_pad_numbers_are_jumpers no)
		(fp_line
			(start -1.524 0.762)
			(end 1.524 0.762)
			(stroke
				(width 0.1524)
				(type default)
			)
			(layer "B.SilkS")
		)
		(fp_line
			(start 1.524 0.762)
			(end 1.524 -0.762)
			(stroke
				(width 0.1524)
				(type default)
			)
			(layer "B.SilkS")
		)
		(fp_line
			(start -1.524 -0.762)
			(end -1.524 0.762)
			(stroke
				(width 0.1524)
				(type default)
			)
			(layer "B.SilkS")
		)
		(fp_line
			(start 1.524 -0.762)
			(end -1.524 -0.762)
			(stroke
				(width 0.1524)
				(type default)
			)
			(layer "B.SilkS")
		)
		(fp_line
			(start -1.1049 0.724916)
			(end -1.1049 -0.724916)
			(stroke
				(width 0.1)
				(type default)
			)
			(layer "B.Fab")
		)
		(fp_line
			(start 1.1049 0.724916)
			(end -1.1049 0.724916)
			(stroke
				(width 0.1)
				(type default)
			)
			(layer "B.Fab")
		)
		(fp_line
			(start -1.1049 -0.724916)
			(end 1.1049 -0.724916)
			(stroke
				(width 0.1)
				(type default)
			)
			(layer "B.Fab")
		)
		(fp_line
			(start 1.1049 -0.724916)
			(end 1.1049 0.724916)
			(stroke
				(width 0.1)
				(type default)
			)
			(layer "B.Fab")
		)
		(pad "1" smd rect
			(at 0.889 0 270)
			(size 1.016 1.27)
			(layers "B.Cu" "B.Mask" "B.Paste")
			(net "PVCCFA_EHV_FIVRA_CPU1")
		)
		(pad "2" smd rect
			(at -0.889 0 270)
			(size 1.016 1.27)
			(layers "B.Cu" "B.Mask" "B.Paste")
			(net "GND")
		)
	)
	(footprint ""
		(layer "B.Cu")
		(at 369.49888 -40.096948 180)
		(property "Reference" "R4115"
			(at 0 0 0)
			(layer "B.SilkS")
			(hide yes)
			(effects
				(font
					(size 1.27 1.27)
				)
				(justify mirror)
			)
		)
		(property "Value" ""
			(at 0 0 0)
			(layer "B.Fab")
			(effects
				(font
					(size 1.27 1.27)
				)
				(justify mirror)
			)
		)
		(duplicate_pad_numbers_are_jumpers no)
		(fp_line
			(start 0.7874 0.4064)
			(end 0.7874 -0.4064)
			(stroke
				(width 0.1524)
				(type default)
			)
			(layer "B.SilkS")
		)
		(fp_line
			(start 0.7874 -0.4064)
			(end -0.7874 -0.4064)
			(stroke
				(width 0.1524)
				(type default)
			)
			(layer "B.SilkS")
		)
		(fp_line
			(start -0.7874 0.4064)
			(end 0.7874 0.4064)
			(stroke
				(width 0.1524)
				(type default)
			)
			(layer "B.SilkS")
		)
		(fp_line
			(start -0.7874 -0.4064)
			(end -0.7874 0.4064)
			(stroke
				(width 0.1524)
				(type default)
			)
			(layer "B.SilkS")
		)
		(fp_line
			(start 0.67945 0.3048)
			(end 0.67945 -0.305054)
			(stroke
				(width 0.1)
				(type default)
			)
			(layer "B.Fab")
		)
		(fp_line
			(start 0.67945 -0.305054)
			(end 0.12065 -0.305054)
			(stroke
				(width 0.1)
				(type default)
			)
			(layer "B.Fab")
		)
		(fp_line
			(start 0.12065 0.3048)
			(end 0.67945 0.3048)
			(stroke
				(width 0.1)
				(type default)
			)
			(layer "B.Fab")
		)
		(fp_line
			(start 0.12065 0.2794)
			(end 0.12065 0.3048)
			(stroke
				(width 0.1)
				(type default)
			)
			(layer "B.Fab")
		)
		(fp_line
			(start 0.12065 -0.2794)
			(end -0.12065 -0.2794)
			(stroke
				(width 0.1)
				(type default)
			)
			(layer "B.Fab")
		)
		(fp_line
			(start 0.12065 -0.305054)
			(end 0.12065 -0.2794)
			(stroke
				(width 0.1)
				(type default)
			)
			(layer "B.Fab")
		)
		(fp_line
			(start -0.120396 0.3048)
			(end -0.120396 0.2794)
			(stroke
				(width 0.1)
				(type default)
			)
			(layer "B.Fab")
		)
		(fp_line
			(start -0.120396 0.2794)
			(end 0.12065 0.2794)
			(stroke
				(width 0.1)
				(type default)
			)
			(layer "B.Fab")
		)
		(fp_line
			(start -0.12065 -0.2794)
			(end -0.12065 -0.3048)
			(stroke
				(width 0.1)
				(type default)
			)
			(layer "B.Fab")
		)
		(fp_line
			(start -0.12065 -0.3048)
			(end -0.67945 -0.3048)
			(stroke
				(width 0.1)
				(type default)
			)
			(layer "B.Fab")
		)
		(fp_line
			(start -0.67945 0.3048)
			(end -0.120396 0.3048)
			(stroke
				(width 0.1)
				(type default)
			)
			(layer "B.Fab")
		)
		(fp_line
			(start -0.67945 -0.3048)
			(end -0.67945 0.3048)
			(stroke
				(width 0.1)
				(type default)
			)
			(layer "B.Fab")
		)
		(pad "1" smd circle
			(at 0.40005 0)
			(size 0 0)
			(layers "B.Cu" "B.Mask" "B.Paste")
			(net "PD_PCH_GPP_E_9")
		)
		(pad "2" smd circle
			(at -0.40005 0)
			(size 0 0)
			(layers "B.Cu" "B.Mask" "B.Paste")
			(net "GND")
		)
	)
)
